(kicad_pcb
	(version 20260206)
	(generator "pcbnew")
	(generator_version "10.0")
	(general
		(thickness 1.6)
		(legacy_teardrops no)
	)
	(paper "A4")
	(title_block
		(title "04192023_DAF0TMB3IC0_F0TG_MB_C_brd_V02_OCP.brd")
		(comment 1 "Grand Teton / footprints 7826-7831 of 8354")
	)
	(layers
		(0 "F.Cu" signal "TOP")
		(4 "In1.Cu" signal "GND")
		(6 "In2.Cu" signal "IN1")
		(8 "In3.Cu" signal "GND1")
		(10 "In4.Cu" signal "IN2")
		(12 "In5.Cu" signal "GND2")
		(14 "In6.Cu" signal "IN3")
		(16 "In7.Cu" signal "GND3")
		(18 "In8.Cu" signal "VCC")
		(20 "In9.Cu" signal "VCC1")
		(22 "In10.Cu" signal "GND4")
		(24 "In11.Cu" signal "IN4")
		(26 "In12.Cu" signal "GND5")
		(28 "In13.Cu" signal "IN5")
		(30 "In14.Cu" signal "GND6")
		(32 "In15.Cu" signal "IN6")
		(34 "In16.Cu" signal "GND7")
		(2 "B.Cu" signal "BOTTOM")
		(9 "F.Adhes" user "F.Adhesive")
		(11 "B.Adhes" user "B.Adhesive")
		(13 "F.Paste" user "Package Geometry/Pastemask Top")
		(15 "B.Paste" user "Package Geometry/Pastemask Bottom")
		(5 "F.SilkS" user "Ref Des/Silkscreen Top")
		(7 "B.SilkS" user "Ref Des/Silkscreen Bottom")
		(1 "F.Mask" user "Board Geometry/Soldermask Top")
		(3 "B.Mask" user "Board Geometry/Soldermask Bottom")
		(17 "Dwgs.User" user "User.Drawings")
		(19 "Cmts.User" user "User.Comments")
		(21 "Eco1.User" user "User.Eco1")
		(23 "Eco2.User" user "User.Eco2")
		(25 "Edge.Cuts" user "Board Geometry/Outline")
		(27 "Margin" user)
		(31 "F.CrtYd" user "Package Geometry/Place Bound Top")
		(29 "B.CrtYd" user "Package Geometry/Place Bound Bottom")
		(35 "F.Fab" user "Ref Des/Assembly Top")
		(33 "B.Fab" user "Ref Des/Assembly Bottom")
	)
	(footprint ""
		(layer "B.Cu")
		(at 440.78525 8.689848)
		(property "Reference" "J8068"
			(at 4.466336 1.99136 270)
			(unlocked yes)
			(layer "B.SilkS")
			(effects
				(font
					(size 0.7874 0.5842)
					(thickness 0.1524)
				)
				(justify left mirror)
			)
		)
		(property "Value" ""
			(at 0 0 0)
			(layer "B.Fab")
			(effects
				(font
					(size 1.27 1.27)
				)
				(justify mirror)
			)
		)
		(duplicate_pad_numbers_are_jumpers no)
		(fp_line
			(start -1.2192 -2.06756)
			(end -1.2192 2.06756)
			(stroke
				(width 0.1524)
				(type default)
			)
			(layer "B.SilkS")
		)
		(fp_line
			(start -1.2192 2.06756)
			(end 1.2192 2.06756)
			(stroke
				(width 0.1524)
				(type default)
			)
			(layer "B.SilkS")
		)
		(fp_line
			(start 1.2192 -2.06756)
			(end -1.2192 -2.06756)
			(stroke
				(width 0.1524)
				(type default)
			)
			(layer "B.SilkS")
		)
		(fp_line
			(start 1.2192 2.06756)
			(end 1.2192 -2.06756)
			(stroke
				(width 0.1524)
				(type default)
			)
			(layer "B.SilkS")
		)
		(pad "" np_thru_hole circle
			(at -3.4671 -1.27 270)
			(size 1.0414 1.0414)
			(drill 1.0414)
			(layers "*.Cu" "*.Mask")
			(clearance 0.381)
			(thermal_gap 0.381)
		)
		(pad "" np_thru_hole circle
			(at -3.4671 1.27 270)
			(size 1.0414 1.0414)
			(drill 1.0414)
			(layers "*.Cu" "*.Mask")
			(clearance 0.381)
			(thermal_gap 0.381)
		)
		(pad "" np_thru_hole circle
			(at 2.8829 -1.27 270)
			(size 1.0414 1.0414)
			(drill 1.0414)
			(layers "*.Cu" "*.Mask")
			(clearance 0.381)
			(thermal_gap 0.381)
		)
		(pad "" np_thru_hole circle
			(at 2.8829 1.27 270)
			(size 1.0414 1.0414)
			(drill 1.0414)
			(layers "*.Cu" "*.Mask")
			(clearance 0.381)
			(thermal_gap 0.381)
		)
		(pad "1" smd rect
			(at -0.8255 -0.249936 270)
			(size 0.3048 0.508)
			(layers "B.Cu" "B.Mask" "B.Paste")
			(net "DELTA_L_85_5INCH_IN4_DP")
		)
		(pad "2" smd rect
			(at -0.8255 0.249936 270)
			(size 0.3048 0.508)
			(layers "B.Cu" "B.Mask" "B.Paste")
			(net "DELTA_L_85_5INCH_IN4_DN")
		)
		(pad "3" smd circle
			(at 0 0 180)
			(size 0 0)
			(layers "B.Cu" "B.Mask" "B.Paste")
			(net "DELTA_L_GND_1")
		)
		(zone
			(layers "F.Cu" "B.Cu" "In1.Cu" "In2.Cu" "In3.Cu" "In4.Cu" "In5.Cu" "In6.Cu"
				"In7.Cu" "In8.Cu" "In9.Cu" "In10.Cu" "In11.Cu" "In12.Cu" "In13.Cu" "In14.Cu"
				"In15.Cu" "In16.Cu"
			)
			(hatch none 0.5)
			(connect_pads
				(clearance 0)
			)
			(min_thickness 0.25)
			(keepout
				(tracks not_allowed)
				(vias allowed)
				(pads allowed)
				(copperpour not_allowed)
				(footprints allowed)
			)
			(placement
				(enabled no)
				(sheetname "")
			)
			(fill
				(thermal_gap 0.5)
				(thermal_bridge_width 0.5)
				(island_removal_mode 0)
			)
			(polygon
				(pts
					(arc
						(start 438.24525 7.419848)
						(mid 436.39105 7.419848)
						(end 438.24525 7.419848)
					)
				)
			)
		)
		(zone
			(layers "F.Cu" "B.Cu" "In1.Cu" "In2.Cu" "In3.Cu" "In4.Cu" "In5.Cu" "In6.Cu"
				"In7.Cu" "In8.Cu" "In9.Cu" "In10.Cu" "In11.Cu" "In12.Cu" "In13.Cu" "In14.Cu"
				"In15.Cu" "In16.Cu"
			)
			(hatch none 0.5)
			(connect_pads
				(clearance 0)
			)
			(min_thickness 0.25)
			(keepout
				(tracks not_allowed)
				(vias allowed)
				(pads allowed)
				(copperpour not_allowed)
				(footprints allowed)
			)
			(placement
				(enabled no)
				(sheetname "")
			)
			(fill
				(thermal_gap 0.5)
				(thermal_bridge_width 0.5)
				(island_removal_mode 0)
			)
			(polygon
				(pts
					(arc
						(start 438.24525 9.959848)
						(mid 436.39105 9.959848)
						(end 438.24525 9.959848)
					)
				)
			)
		)
		(zone
			(layers "F.Cu" "B.Cu" "In1.Cu" "In2.Cu" "In3.Cu" "In4.Cu" "In5.Cu" "In6.Cu"
				"In7.Cu" "In8.Cu" "In9.Cu" "In10.Cu" "In11.Cu" "In12.Cu" "In13.Cu" "In14.Cu"
				"In15.Cu" "In16.Cu"
			)
			(hatch none 0.5)
			(connect_pads
				(clearance 0)
			)
			(min_thickness 0.25)
			(keepout
				(tracks not_allowed)
				(vias allowed)
				(pads allowed)
				(copperpour not_allowed)
				(footprints allowed)
			)
			(placement
				(enabled no)
				(sheetname "")
			)
			(fill
				(thermal_gap 0.5)
				(thermal_bridge_width 0.5)
				(island_removal_mode 0)
			)
			(polygon
				(pts
					(arc
						(start 444.59525 7.419848)
						(mid 442.74105 7.419848)
						(end 444.59525 7.419848)
					)
				)
			)
		)
		(zone
			(layers "F.Cu" "B.Cu" "In1.Cu" "In2.Cu" "In3.Cu" "In4.Cu" "In5.Cu" "In6.Cu"
				"In7.Cu" "In8.Cu" "In9.Cu" "In10.Cu" "In11.Cu" "In12.Cu" "In13.Cu" "In14.Cu"
				"In15.Cu" "In16.Cu"
			)
			(hatch none 0.5)
			(connect_pads
				(clearance 0)
			)
			(min_thickness 0.25)
			(keepout
				(tracks not_allowed)
				(vias allowed)
				(pads allowed)
				(copperpour not_allowed)
				(footprints allowed)
			)
			(placement
				(enabled no)
				(sheetname "")
			)
			(fill
				(thermal_gap 0.5)
				(thermal_bridge_width 0.5)
				(island_removal_mode 0)
			)
			(polygon
				(pts
					(arc
						(start 444.59525 9.959848)
						(mid 442.74105 9.959848)
						(end 444.59525 9.959848)
					)
				)
			)
		)
		(zone
			(layer "B.Cu")
			(hatch none 0.5)
			(connect_pads
				(clearance 0)
			)
			(min_thickness 0.25)
			(keepout
				(tracks not_allowed)
				(vias allowed)
				(pads allowed)
				(copperpour not_allowed)
				(footprints allowed)
			)
			(placement
				(enabled no)
				(sheetname "")
			)
			(fill
				(thermal_gap 0.5)
				(thermal_bridge_width 0.5)
				(island_removal_mode 0)
			)
			(polygon
				(pts
					(xy 439.66765 8.141208) (xy 439.66765 8.236712) (xy 440.26455 8.236712) (xy 440.26455 8.643112)
					(xy 439.66765 8.643112) (xy 439.66765 8.736584) (xy 440.26455 8.736584) (xy 440.26455 9.142984)
					(xy 439.66765 9.142984) (xy 439.66765 9.238488) (xy 440.36615 9.238488) (xy 440.36615 8.141208)
				)
			)
		)
	)
	(footprint ""
		(layer "B.Cu")
		(at 241.758978 -315.95568 -90)
		(property "Reference" "PC6511"
			(at 0 0 90)
			(layer "B.SilkS")
			(hide yes)
			(effects
				(font
					(size 1.27 1.27)
				)
				(justify mirror)
			)
		)
		(property "Value" ""
			(at 0 0 90)
			(layer "B.Fab")
			(effects
				(font
					(size 1.27 1.27)
				)
				(justify mirror)
			)
		)
		(duplicate_pad_numbers_are_jumpers no)
		(fp_line
			(start -1.524 0.762)
			(end 1.524 0.762)
			(stroke
				(width 0.1524)
				(type default)
			)
			(layer "B.SilkS")
		)
		(fp_line
			(start 1.524 0.762)
			(end 1.524 -0.762)
			(stroke
				(width 0.1524)
				(type default)
			)
			(layer "B.SilkS")
		)
		(fp_line
			(start -1.524 -0.762)
			(end -1.524 0.762)
			(stroke
				(width 0.1524)
				(type default)
			)
			(layer "B.SilkS")
		)
		(fp_line
			(start 1.524 -0.762)
			(end -1.524 -0.762)
			(stroke
				(width 0.1524)
				(type default)
			)
			(layer "B.SilkS")
		)
		(fp_line
			(start -1.1049 0.724916)
			(end -1.1049 -0.724916)
			(stroke
				(width 0.1)
				(type default)
			)
			(layer "B.Fab")
		)
		(fp_line
			(start 1.1049 0.724916)
			(end -1.1049 0.724916)
			(stroke
				(width 0.1)
				(type default)
			)
			(layer "B.Fab")
		)
		(fp_line
			(start -1.1049 -0.724916)
			(end 1.1049 -0.724916)
			(stroke
				(width 0.1)
				(type default)
			)
			(layer "B.Fab")
		)
		(fp_line
			(start 1.1049 -0.724916)
			(end 1.1049 0.724916)
			(stroke
				(width 0.1)
				(type default)
			)
			(layer "B.Fab")
		)
		(pad "1" smd rect
			(at 0.889 0 270)
			(size 1.016 1.27)
			(layers "B.Cu" "B.Mask" "B.Paste")
			(net "P1V8_CPU0_RT_1D")
		)
		(pad "2" smd rect
			(at -0.889 0 270)
			(size 1.016 1.27)
			(layers "B.Cu" "B.Mask" "B.Paste")
			(net "GND")
		)
	)
	(footprint ""
		(layer "B.Cu")
		(at 428.98695 -31.181548 180)
		(property "Reference" "R6106"
			(at 0 0 0)
			(layer "B.SilkS")
			(hide yes)
			(effects
				(font
					(size 1.27 1.27)
				)
				(justify mirror)
			)
		)
		(property "Value" ""
			(at 0 0 0)
			(layer "B.Fab")
			(effects
				(font
					(size 1.27 1.27)
				)
				(justify mirror)
			)
		)
		(duplicate_pad_numbers_are_jumpers no)
		(fp_line
			(start 0.7874 0.4064)
			(end 0.7874 -0.4064)
			(stroke
				(width 0.1524)
				(type default)
			)
			(layer "B.SilkS")
		)
		(fp_line
			(start 0.7874 -0.4064)
			(end -0.7874 -0.4064)
			(stroke
				(width 0.1524)
				(type default)
			)
			(layer "B.SilkS")
		)
		(fp_line
			(start -0.7874 0.4064)
			(end 0.7874 0.4064)
			(stroke
				(width 0.1524)
				(type default)
			)
			(layer "B.SilkS")
		)
		(fp_line
			(start -0.7874 -0.4064)
			(end -0.7874 0.4064)
			(stroke
				(width 0.1524)
				(type default)
			)
			(layer "B.SilkS")
		)
		(fp_line
			(start 0.67945 0.3048)
			(end 0.67945 -0.305054)
			(stroke
				(width 0.1)
				(type default)
			)
			(layer "B.Fab")
		)
		(fp_line
			(start 0.67945 -0.305054)
			(end 0.12065 -0.305054)
			(stroke
				(width 0.1)
				(type default)
			)
			(layer "B.Fab")
		)
		(fp_line
			(start 0.12065 0.3048)
			(end 0.67945 0.3048)
			(stroke
				(width 0.1)
				(type default)
			)
			(layer "B.Fab")
		)
		(fp_line
			(start 0.12065 0.2794)
			(end 0.12065 0.3048)
			(stroke
				(width 0.1)
				(type default)
			)
			(layer "B.Fab")
		)
		(fp_line
			(start 0.12065 -0.2794)
			(end -0.12065 -0.2794)
			(stroke
				(width 0.1)
				(type default)
			)
			(layer "B.Fab")
		)
		(fp_line
			(start 0.12065 -0.305054)
			(end 0.12065 -0.2794)
			(stroke
				(width 0.1)
				(type default)
			)
			(layer "B.Fab")
		)
		(fp_line
			(start -0.120396 0.3048)
			(end -0.120396 0.2794)
			(stroke
				(width 0.1)
				(type default)
			)
			(layer "B.Fab")
		)
		(fp_line
			(start -0.120396 0.2794)
			(end 0.12065 0.2794)
			(stroke
				(width 0.1)
				(type default)
			)
			(layer "B.Fab")
		)
		(fp_line
			(start -0.12065 -0.2794)
			(end -0.12065 -0.3048)
			(stroke
				(width 0.1)
				(type default)
			)
			(layer "B.Fab")
		)
		(fp_line
			(start -0.12065 -0.3048)
			(end -0.67945 -0.3048)
			(stroke
				(width 0.1)
				(type default)
			)
			(layer "B.Fab")
		)
		(fp_line
			(start -0.67945 0.3048)
			(end -0.120396 0.3048)
			(stroke
				(width 0.1)
				(type default)
			)
			(layer "B.Fab")
		)
		(fp_line
			(start -0.67945 -0.3048)
			(end -0.67945 0.3048)
			(stroke
				(width 0.1)
				(type default)
			)
			(layer "B.Fab")
		)
		(pad "1" smd circle
			(at 0.40005 0)
			(size 0 0)
			(layers "B.Cu" "B.Mask" "B.Paste")
			(net "PVDD18_S5_P0")
		)
		(pad "2" smd circle
			(at -0.40005 0)
			(size 0 0)
			(layers "B.Cu" "B.Mask" "B.Paste")
			(net "FM_PASSWORD_CLEAR_N")
		)
	)
	(footprint ""
		(layer "B.Cu")
		(at 242.062 -328.168)
		(property "Reference" "L24"
			(at 0 0 0)
			(layer "B.SilkS")
			(hide yes)
			(effects
				(font
					(size 1.27 1.27)
				)
				(justify mirror)
			)
		)
		(property "Value" ""
			(at 0 0 0)
			(layer "B.Fab")
			(effects
				(font
					(size 1.27 1.27)
				)
				(justify mirror)
			)
		)
		(duplicate_pad_numbers_are_jumpers no)
		(fp_line
			(start -1.27 0.5842)
			(end -1.27 -0.5842)
			(stroke
				(width 0.1524)
				(type default)
			)
			(layer "B.SilkS")
		)
		(fp_line
			(start -1.27 0.5842)
			(end 1.27 0.5842)
			(stroke
				(width 0.1524)
				(type default)
			)
			(layer "B.SilkS")
		)
		(fp_line
			(start 1.27 -0.5842)
			(end -1.27 -0.5842)
			(stroke
				(width 0.1524)
				(type default)
			)
			(layer "B.SilkS")
		)
		(fp_line
			(start 1.27 -0.5588)
			(end 1.27 -0.5842)
			(stroke
				(width 0.1524)
				(type default)
			)
			(layer "B.SilkS")
		)
		(fp_line
			(start 1.27 0.5842)
			(end 1.27 -0.5842)
			(stroke
				(width 0.1524)
				(type default)
			)
			(layer "B.SilkS")
		)
		(fp_line
			(start -1.1938 -0.406654)
			(end -1.1938 0.4064)
			(stroke
				(width 0.1)
				(type default)
			)
			(layer "B.Fab")
		)
		(fp_line
			(start -1.1938 0.4064)
			(end -0.9144 0.4064)
			(stroke
				(width 0.1)
				(type default)
			)
			(layer "B.Fab")
		)
		(fp_line
			(start -0.9144 -0.508)
			(end -0.9144 -0.406654)
			(stroke
				(width 0.1)
				(type default)
			)
			(layer "B.Fab")
		)
		(fp_line
			(start -0.9144 -0.406654)
			(end -1.1938 -0.406654)
			(stroke
				(width 0.1)
				(type default)
			)
			(layer "B.Fab")
		)
		(fp_line
			(start -0.9144 0.4064)
			(end -0.9144 0.508)
			(stroke
				(width 0.1)
				(type default)
			)
			(layer "B.Fab")
		)
		(fp_line
			(start -0.9144 0.508)
			(end 0.9144 0.508)
			(stroke
				(width 0.1)
				(type default)
			)
			(layer "B.Fab")
		)
		(fp_line
			(start 0.9144 -0.508)
			(end -0.9144 -0.508)
			(stroke
				(width 0.1)
				(type default)
			)
			(layer "B.Fab")
		)
		(fp_line
			(start 0.9144 -0.406654)
			(end 0.9144 -0.508)
			(stroke
				(width 0.1)
				(type default)
			)
			(layer "B.Fab")
		)
		(fp_line
			(start 0.9144 0.406654)
			(end 1.194308 0.406654)
			(stroke
				(width 0.1)
				(type default)
			)
			(layer "B.Fab")
		)
		(fp_line
			(start 0.9144 0.508)
			(end 0.9144 0.406654)
			(stroke
				(width 0.1)
				(type default)
			)
			(layer "B.Fab")
		)
		(fp_line
			(start 1.194308 -0.406654)
			(end 0.9144 -0.406654)
			(stroke
				(width 0.1)
				(type default)
			)
			(layer "B.Fab")
		)
		(fp_line
			(start 1.194308 0.406654)
			(end 1.194308 -0.406654)
			(stroke
				(width 0.1)
				(type default)
			)
			(layer "B.Fab")
		)
		(pad "1" smd rect
			(at 0.7366 0 270)
			(size 0.7112 0.8128)
			(layers "B.Cu" "B.Mask" "B.Paste")
			(net "P3V3_MAX11617_2_VDD")
		)
		(pad "2" smd rect
			(at -0.7366 0 270)
			(size 0.7112 0.8128)
			(layers "B.Cu" "B.Mask" "B.Paste")
			(net "P3V3_AUX")
		)
	)
	(footprint ""
		(layer "B.Cu")
		(at 130.218434 -388.011162 -90)
		(property "Reference" "C496"
			(at 0 0 90)
			(layer "B.SilkS")
			(hide yes)
			(effects
				(font
					(size 1.27 1.27)
				)
				(justify mirror)
			)
		)
		(property "Value" ""
			(at 0 0 90)
			(layer "B.Fab")
			(effects
				(font
					(size 1.27 1.27)
				)
				(justify mirror)
			)
		)
		(duplicate_pad_numbers_are_jumpers no)
		(fp_line
			(start -0.299974 0.150114)
			(end 0.299974 0.150114)
			(stroke
				(width 0.1)
				(type default)
			)
			(layer "B.Fab")
		)
		(fp_line
			(start 0.299974 0.150114)
			(end 0.299974 -0.150114)
			(stroke
				(width 0.1)
				(type default)
			)
			(layer "B.Fab")
		)
		(fp_line
			(start -0.299974 -0.150114)
			(end -0.299974 0.150114)
			(stroke
				(width 0.1)
				(type default)
			)
			(layer "B.Fab")
		)
		(fp_line
			(start 0.299974 -0.150114)
			(end -0.299974 -0.150114)
			(stroke
				(width 0.1)
				(type default)
			)
			(layer "B.Fab")
		)
		(pad "1" smd rect
			(at 0.2667 0 90)
			(size 0.3048 0.381)
			(layers "B.Cu" "B.Mask" "B.Paste")
			(net "P0V9_CPU1_RT3_2A")
		)
		(pad "2" smd rect
			(at -0.2667 0 90)
			(size 0.3048 0.381)
			(layers "B.Cu" "B.Mask" "B.Paste")
			(net "GND")
		)
	)
	(footprint ""
		(layer "B.Cu")
		(at 326.742806 -416.899344 90)
		(property "Reference" "C6548"
			(at 0 0 90)
			(layer "B.SilkS")
			(hide yes)
			(effects
				(font
					(size 1.27 1.27)
				)
				(justify mirror)
			)
		)
		(property "Value" ""
			(at 0 0 90)
			(layer "B.Fab")
			(effects
				(font
					(size 1.27 1.27)
				)
				(justify mirror)
			)
		)
		(duplicate_pad_numbers_are_jumpers no)
		(fp_line
			(start 0.299974 -0.150114)
			(end -0.299974 -0.150114)
			(stroke
				(width 0.1)
				(type default)
			)
			(layer "B.Fab")
		)
		(fp_line
			(start -0.299974 -0.150114)
			(end -0.299974 0.150114)
			(stroke
				(width 0.1)
				(type default)
			)
			(layer "B.Fab")
		)
		(fp_line
			(start 0.299974 0.150114)
			(end 0.299974 -0.150114)
			(stroke
				(width 0.1)
				(type default)
			)
			(layer "B.Fab")
		)
		(fp_line
			(start -0.299974 0.150114)
			(end 0.299974 0.150114)
			(stroke
				(width 0.1)
				(type default)
			)
			(layer "B.Fab")
		)
		(pad "1" smd rect
			(at 0.2667 0 270)
			(size 0.3048 0.381)
			(layers "B.Cu" "B.Mask" "B.Paste")
			(net "P5E_CPU0_P1_TX_BUF_C_DN<7>")
		)
		(pad "2" smd rect
			(at -0.2667 0 270)
			(size 0.3048 0.381)
			(layers "B.Cu" "B.Mask" "B.Paste")
			(net "P5E_CPU0_P1_TX_BUF_DN<7>")
		)
	)
)
